FILE_TYPE = CONNECTIVITY;
{Allegro Design Entry HDL 17.2-2016 S081 (4005846) 1/11/2022}
"PAGE_NUMBER" = 52;
0"NC";
1"P5E_CPU1_P2_TX_DP<15:0>";
2"P5E_CPU1_P2_TX_DN<15:0>";
3"P5E_CPU1_P3_TX_DN<15:0>";
4"P5E_CPU1_P3_TX_DP<15:0>";
5"P5E_CPU1_P2_RX_DP<15:0>";
6"P5E_CPU1_P2_RX_DN<15:0>";
7"P5E_CPU1_P3_RX_DP<15:0>";
8"P5E_CPU1_P3_RX_DN<15:0>";
9"P5E_CPU1_P2_RX_DN<9>";
10"P5E_CPU1_P2_RX_DP<6>";
11"P5E_CPU1_P2_RX_DN<5>";
12"P5E_CPU1_P2_RX_DP<5>";
13"P5E_CPU1_P2_RX_DP<0>";
14"P5E_CPU1_P2_RX_DN<0>";
15"P5E_CPU1_P2_RX_DP<1>";
16"P5E_CPU1_P2_RX_DN<3>";
17"P5E_CPU1_P3_RX_DN<15>";
18"P5E_CPU1_P3_RX_DP<15>";
19"P5E_CPU1_P3_RX_DN<14>";
20"P5E_CPU1_P3_RX_DP<14>";
21"P5E_CPU1_P3_RX_DN<13>";
22"P5E_CPU1_P3_RX_DP<13>";
23"P5E_CPU1_P3_RX_DN<12>";
24"P5E_CPU1_P3_RX_DP<12>";
25"P5E_CPU1_P3_RX_DN<11>";
26"P5E_CPU1_P3_RX_DP<11>";
27"P5E_CPU1_P3_RX_DN<10>";
28"P5E_CPU1_P3_RX_DP<10>";
29"P5E_CPU1_P3_RX_DN<9>";
30"P5E_CPU1_P3_RX_DP<9>";
31"P5E_CPU1_P3_RX_DN<8>";
32"P5E_CPU1_P3_RX_DP<8>";
33"P5E_CPU1_P3_RX_DN<7>";
34"P5E_CPU1_P3_RX_DP<7>";
35"P5E_CPU1_P3_RX_DN<6>";
36"P5E_CPU1_P3_RX_DP<6>";
37"P5E_CPU1_P3_RX_DN<5>";
38"P5E_CPU1_P3_RX_DP<5>";
39"P5E_CPU1_P3_RX_DN<4>";
40"P5E_CPU1_P3_RX_DP<4>";
41"P5E_CPU1_P3_RX_DN<3>";
42"P5E_CPU1_P3_RX_DP<3>";
43"P5E_CPU1_P3_RX_DN<2>";
44"P5E_CPU1_P3_RX_DP<2>";
45"P5E_CPU1_P3_RX_DN<1>";
46"P5E_CPU1_P3_RX_DP<1>";
47"P5E_CPU1_P3_RX_DN<0>";
48"P5E_CPU1_P3_RX_DP<0>";
49"P5E_CPU1_P2_RX_DN<7>";
50"P5E_CPU1_P2_RX_DN<6>";
51"P5E_CPU1_P2_RX_DP<7>";
52"P5E_CPU1_P2_RX_DN<15>";
53"P5E_CPU1_P2_RX_DP<15>";
54"P5E_CPU1_P2_RX_DN<14>";
55"P5E_CPU1_P2_RX_DP<14>";
56"P5E_CPU1_P2_RX_DN<13>";
57"P5E_CPU1_P2_RX_DP<13>";
58"P5E_CPU1_P2_RX_DN<12>";
59"P5E_CPU1_P2_RX_DP<12>";
60"P5E_CPU1_P2_RX_DN<11>";
61"P5E_CPU1_P2_RX_DP<11>";
62"P5E_CPU1_P2_RX_DN<10>";
63"P5E_CPU1_P2_RX_DP<10>";
64"P5E_CPU1_P2_RX_DP<9>";
65"P5E_CPU1_P2_RX_DN<8>";
66"P5E_CPU1_P2_RX_DP<8>";
67"P5E_CPU1_P2_RX_DN<4>";
68"P5E_CPU1_P2_RX_DN<2>";
69"P5E_CPU1_P2_RX_DP<4>";
70"P5E_CPU1_P2_RX_DN<1>";
71"P5E_CPU1_P2_RX_DP<3>";
72"P5E_CPU1_P2_RX_DP<2>";
73"P5E_CPU1_P3_TX_DP<15>";
74"P5E_CPU1_P3_TX_DN<15>";
75"P5E_CPU1_P3_TX_DP<14>";
76"P5E_CPU1_P3_TX_DN<14>";
77"P5E_CPU1_P3_TX_DP<13>";
78"P5E_CPU1_P3_TX_DN<13>";
79"P5E_CPU1_P3_TX_DP<12>";
80"P5E_CPU1_P3_TX_DN<12>";
81"P5E_CPU1_P3_TX_DP<11>";
82"P5E_CPU1_P3_TX_DN<11>";
83"P5E_CPU1_P3_TX_DP<10>";
84"P5E_CPU1_P3_TX_DN<10>";
85"P5E_CPU1_P3_TX_DP<9>";
86"P5E_CPU1_P3_TX_DN<9>";
87"P5E_CPU1_P3_TX_DP<8>";
88"P5E_CPU1_P3_TX_DN<8>";
89"P5E_CPU1_P3_TX_DP<7>";
90"P5E_CPU1_P3_TX_DN<7>";
91"P5E_CPU1_P3_TX_DP<6>";
92"P5E_CPU1_P3_TX_DN<6>";
93"P5E_CPU1_P3_TX_DP<5>";
94"P5E_CPU1_P3_TX_DN<5>";
95"P5E_CPU1_P3_TX_DP<4>";
96"P5E_CPU1_P3_TX_DN<4>";
97"P5E_CPU1_P3_TX_DP<3>";
98"P5E_CPU1_P3_TX_DN<3>";
99"P5E_CPU1_P3_TX_DP<2>";
100"P5E_CPU1_P3_TX_DN<2>";
101"P5E_CPU1_P3_TX_DP<1>";
102"P5E_CPU1_P3_TX_DN<1>";
103"P5E_CPU1_P3_TX_DP<0>";
104"P5E_CPU1_P3_TX_DN<0>";
105"P5E_CPU1_P2_TX_DN<7>";
106"P5E_CPU1_P2_TX_DN<6>";
107"P5E_CPU1_P2_TX_DN<5>";
108"P5E_CPU1_P2_TX_DP<7>";
109"P5E_CPU1_P2_TX_DP<6>";
110"P5E_CPU1_P2_TX_DN<15>";
111"P5E_CPU1_P2_TX_DP<15>";
112"P5E_CPU1_P2_TX_DN<14>";
113"P5E_CPU1_P2_TX_DP<14>";
114"P5E_CPU1_P2_TX_DN<13>";
115"P5E_CPU1_P2_TX_DP<13>";
116"P5E_CPU1_P2_TX_DN<12>";
117"P5E_CPU1_P2_TX_DP<12>";
118"P5E_CPU1_P2_TX_DN<11>";
119"P5E_CPU1_P2_TX_DP<11>";
120"P5E_CPU1_P2_TX_DN<10>";
121"P5E_CPU1_P2_TX_DP<10>";
122"P5E_CPU1_P2_TX_DN<9>";
123"P5E_CPU1_P2_TX_DP<9>";
124"P5E_CPU1_P2_TX_DN<8>";
125"P5E_CPU1_P2_TX_DP<8>";
126"P5E_CPU1_P2_TX_DN<4>";
127"P5E_CPU1_P2_TX_DN<3>";
128"P5E_CPU1_P2_TX_DP<5>";
129"P5E_CPU1_P2_TX_DN<2>";
130"P5E_CPU1_P2_TX_DP<4>";
131"P5E_CPU1_P2_TX_DN<1>";
132"P5E_CPU1_P2_TX_DP<3>";
133"P5E_CPU1_P2_TX_DN<0>";
134"P5E_CPU1_P2_TX_DP<2>";
135"P5E_CPU1_P2_TX_DP<1>";
136"P5E_CPU1_P2_TX_DP<0>";
%"GENOA_SP5"
"18","(-4625,2350)","0","pure_quanta","I147";
;
LOCATION"U26"
$SEC"18"
CDS_SEC"18"
MATERIAL"IO"
VALUE"SOCKET6096_13568-001"
PART_NUMBER"DGA^6000030"
PART_TYPE"SMLF"
CDS_LIB"pure_quanta"
CDS_LMAN_SYM_OUTLINE"-600,950,600,-950"
NEEDS_NO_SIZE"TRUE";
"P3_TXN15"
$PN"CE23"73;
"P3_TXP15"
$PN"CE24"74;
"P3_TXN14"
$PN"CG23"75;
"P3_TXP14"
$PN"CG24"76;
"P3_TXN13"
$PN"CC23"77;
"P3_TXP13"
$PN"CC24"78;
"P3_TXN12"
$PN"CE26"79;
"P3_TXP12"
$PN"CE27"80;
"P3_TXN11"
$PN"CG26"81;
"P3_TXP11"
$PN"CG27"82;
"P3_TXN10"
$PN"CC26"83;
"P3_TXP10"
$PN"CC27"84;
"P3_TXN9"
$PN"CE29"85;
"P3_TXP9"
$PN"CE30"86;
"P3_TXN8"
$PN"CG29"87;
"P3_TXP8"
$PN"CG30"88;
"P3_TXN7"
$PN"CC29"89;
"P3_TXP7"
$PN"CC30"90;
"P3_TXN6"
$PN"CE32"91;
"P3_TXP6"
$PN"CE33"92;
"P3_TXN5"
$PN"CG32"93;
"P3_TXP5"
$PN"CG33"94;
"P3_TXN4"
$PN"CJ32"95;
"P3_TXP4"
$PN"CJ33"96;
"P3_TXN3"
$PN"CC32"97;
"P3_TXP3"
$PN"CC33"98;
"P3_TXN2"
$PN"CH35"99;
"P3_TXP2"
$PN"CH36"100;
"P3_TXN1"
$PN"CF35"101;
"P3_TXP1"
$PN"CF36"102;
"P3_TXN0"
$PN"CD35"103;
"P3_TXP0"
$PN"CD36"104;
"P3_RXN15"
$PN"CU24"17;
"P3_RXP15"
$PN"CU23"18;
"P3_RXN14"
$PN"DA24"19;
"P3_RXP14"
$PN"DA23"20;
"P3_RXN13"
$PN"DC24"21;
"P3_RXP13"
$PN"DC23"22;
"P3_RXN12"
$PN"CW24"23;
"P3_RXP12"
$PN"CW23"24;
"P3_RXN11"
$PN"DA27"25;
"P3_RXP11"
$PN"DA26"26;
"P3_RXN10"
$PN"DC27"27;
"P3_RXP10"
$PN"DC26"28;
"P3_RXN9"
$PN"CW27"29;
"P3_RXP9"
$PN"CW26"30;
"P3_RXN8"
$PN"DA30"31;
"P3_RXP8"
$PN"DA29"32;
"P3_RXN7"
$PN"DC30"33;
"P3_RXP7"
$PN"DC29"34;
"P3_RXN6"
$PN"CW30"35;
"P3_RXP6"
$PN"CW29"36;
"P3_RXN5"
$PN"DA33"37;
"P3_RXP5"
$PN"DA32"38;
"P3_RXN4"
$PN"DC33"39;
"P3_RXP4"
$PN"DC32"40;
"P3_RXN3"
$PN"CW33"41;
"P3_RXP3"
$PN"CW32"42;
"P3_RXN2"
$PN"DB36"43;
"P3_RXP2"
$PN"DB35"44;
"P3_RXN1"
$PN"CY36"45;
"P3_RXP1"
$PN"CY35"46;
"P3_RXN0"
$PN"CV36"47;
"P3_RXP0"
$PN"CV35"48;
%"GENOA_SP5"
"17","(-4625,4850)","0","pure_quanta","I148";
;
LOCATION"U26"
$SEC"17"
CDS_SEC"17"
MATERIAL"IO"
VALUE"SOCKET6096_13568-001"
PART_NUMBER"DGA^6000030"
PART_TYPE"SMLF"
CDS_LIB"pure_quanta"
CDS_LMAN_SYM_OUTLINE"-600,950,600,-950"
NEEDS_NO_SIZE"TRUE";
"P2_RXN7"
$PN"CU30"49;
"P2_RXN6"
$PN"CN30"50;
"P2_RXN5"
$PN"CR33"11;
"P2_RXP7"
$PN"CU29"51;
"P2_TXN7"
$PN"BU29"105;
"P2_RXN4"
$PN"CU33"67;
"P2_RXP6"
$PN"CN29"10;
"P2_TXN6"
$PN"BW32"106;
"P2_RXN3"
$PN"CN33"16;
"P2_RXP5"
$PN"CR32"12;
"P2_TXN5"
$PN"CA32"107;
"P2_TXP7"
$PN"BU30"108;
"P2_RXN2"
$PN"CT36"68;
"P2_RXP4"
$PN"CU32"69;
"P2_TXN4"
$PN"BU32"126;
"P2_TXP6"
$PN"BW33"109;
"P2_RXN1"
$PN"CP36"70;
"P2_RXP3"
$PN"CN32"71;
"P2_TXN3"
$PN"BY35"127;
"P2_TXP5"
$PN"CA33"128;
"P2_RXN0"
$PN"CM36"14;
"P2_RXP2"
$PN"CT35"72;
"P2_TXN2"
$PN"CB35"129;
"P2_TXP4"
$PN"BU33"130;
"P2_RXP1"
$PN"CP35"15;
"P2_TXN1"
$PN"BV35"131;
"P2_TXP3"
$PN"BY36"132;
"P2_RXP0"
$PN"CM35"13;
"P2_TXN0"
$PN"BT35"133;
"P2_TXP2"
$PN"CB36"134;
"P2_TXP1"
$PN"BV36"135;
"P2_TXP0"
$PN"BT36"136;
"P2_TXN15"
$PN"BW23"110;
"P2_TXP15"
$PN"BW24"111;
"P2_TXN14"
$PN"CA23"112;
"P2_TXP14"
$PN"CA24"113;
"P2_TXN13"
$PN"BU23"114;
"P2_TXP13"
$PN"BU24"115;
"P2_TXN12"
$PN"BW26"116;
"P2_TXP12"
$PN"BW27"117;
"P2_TXN11"
$PN"CA26"118;
"P2_TXP11"
$PN"CA27"119;
"P2_TXN10"
$PN"BU26"120;
"P2_TXP10"
$PN"BU27"121;
"P2_TXN9"
$PN"BW29"122;
"P2_TXP9"
$PN"BW30"123;
"P2_TXN8"
$PN"CA29"124;
"P2_TXP8"
$PN"CA30"125;
"P2_RXN15"
$PN"CN24"52;
"P2_RXP15"
$PN"CN23"53;
"P2_RXN14"
$PN"CR24"54;
"P2_RXP14"
$PN"CR23"55;
"P2_RXN13"
$PN"CL24"56;
"P2_RXP13"
$PN"CL23"57;
"P2_RXN12"
$PN"CN27"58;
"P2_RXP12"
$PN"CN26"59;
"P2_RXN11"
$PN"CR27"60;
"P2_RXP11"
$PN"CR26"61;
"P2_RXN10"
$PN"CU27"62;
"P2_RXP10"
$PN"CU26"63;
"P2_RXN9"
$PN"CL27"9;
"P2_RXP9"
$PN"CL26"64;
"P2_RXN8"
$PN"CR30"65;
"P2_RXP8"
$PN"CR29"66;
%"TAP"
"6","(-3450,5650)","2","mstr_standard","I151";
;
CDS_LIB"mstr_standard"
BOM_COST"IO_SLOT"
BODY_TYPE"PLUMBING"
HDL_TAP"TRUE"
ROOM"RISER1";
"B \NAC \NWC"1;
"S \NAC"
BN"0"136;
%"TAP"
"6","(-3300,5500)","2","mstr_standard","I152";
;
CDS_LIB"mstr_standard"
BOM_COST"IO_SLOT"
BODY_TYPE"PLUMBING"
HDL_TAP"TRUE"
ROOM"RISER1";
"B \NAC \NWC"2;
"S \NAC"
BN"1"131;
%"TAP"
"6","(-3300,5400)","2","standard","I153";
;
CDS_LIB"standard"
BOM_COST"IO_SLOT"
BODY_TYPE"PLUMBING"
HDL_TAP"TRUE"
ROOM"RISER1";
"B \NAC \NWC"2;
"S \NAC"
BN"2"129;
%"TAP"
"6","(-3300,5600)","2","mstr_standard","I154";
;
BOM_COST"IO_SLOT"
CDS_LIB"mstr_standard"
BODY_TYPE"PLUMBING"
HDL_TAP"TRUE"
ROOM"RISER1";
"B \NAC \NWC"2;
"S \NAC"
BN"0"133;
%"TAP"
"6","(-3450,5550)","2","mstr_standard","I155";
;
CDS_LIB"mstr_standard"
BOM_COST"IO_SLOT"
BODY_TYPE"PLUMBING"
HDL_TAP"TRUE"
ROOM"RISER1";
"B \NAC \NWC"1;
"S \NAC"
BN"1"135;
%"TAP"
"6","(-3450,5450)","2","standard","I156";
;
CDS_LIB"standard"
BOM_COST"IO_SLOT"
BODY_TYPE"PLUMBING"
HDL_TAP"TRUE"
ROOM"RISER1";
"B \NAC \NWC"1;
"S \NAC"
BN"2"134;
%"TAP"
"6","(-3300,5300)","2","standard","I157";
;
CDS_LIB"standard"
BOM_COST"IO_SLOT"
BODY_TYPE"PLUMBING"
HDL_TAP"TRUE"
ROOM"RISER1";
"B \NAC \NWC"2;
"S \NAC"
BN"3"127;
%"TAP"
"6","(-3300,5200)","2","standard","I158";
;
CDS_LIB"standard"
BOM_COST"IO_SLOT"
BODY_TYPE"PLUMBING"
HDL_TAP"TRUE"
ROOM"RISER1";
"B \NAC \NWC"2;
"S \NAC"
BN"4"126;
%"TAP"
"6","(-3450,5250)","2","standard","I159";
;
CDS_LIB"standard"
BOM_COST"IO_SLOT"
BODY_TYPE"PLUMBING"
HDL_TAP"TRUE"
ROOM"RISER1";
"B \NAC \NWC"1;
"S \NAC"
BN"4"130;
%"TAP"
"6","(-3450,5350)","2","standard","I160";
;
CDS_LIB"standard"
BOM_COST"IO_SLOT"
BODY_TYPE"PLUMBING"
HDL_TAP"TRUE"
ROOM"RISER1";
"B \NAC \NWC"1;
"S \NAC"
BN"3"132;
%"TAP"
"6","(-3450,5150)","2","standard","I161";
;
CDS_LIB"standard"
BOM_COST"IO_SLOT"
BODY_TYPE"PLUMBING"
HDL_TAP"TRUE"
ROOM"RISER1";
"B \NAC \NWC"1;
"S \NAC"
BN"5"128;
%"TAP"
"6","(-3300,5000)","2","standard","I162";
;
CDS_LIB"standard"
BOM_COST"IO_SLOT"
BODY_TYPE"PLUMBING"
HDL_TAP"TRUE"
ROOM"RISER1";
"B \NAC \NWC"2;
"S \NAC"
BN"6"106;
%"TAP"
"6","(-3300,5100)","2","standard","I163";
;
CDS_LIB"standard"
BOM_COST"IO_SLOT"
BODY_TYPE"PLUMBING"
HDL_TAP"TRUE"
ROOM"RISER1";
"B \NAC \NWC"2;
"S \NAC"
BN"5"107;
%"TAP"
"6","(-3300,4900)","2","standard","I164";
;
CDS_LIB"standard"
BOM_COST"IO_SLOT"
BODY_TYPE"PLUMBING"
HDL_TAP"TRUE"
ROOM"RISER1";
"B \NAC \NWC"2;
"S \NAC"
BN"7"105;
%"TAP"
"6","(-3450,4950)","2","standard","I165";
;
CDS_LIB"standard"
BOM_COST"IO_SLOT"
BODY_TYPE"PLUMBING"
HDL_TAP"TRUE"
ROOM"RISER1";
"B \NAC \NWC"1;
"S \NAC"
BN"7"108;
%"TAP"
"6","(-3450,5050)","2","standard","I166";
;
CDS_LIB"standard"
BOM_COST"IO_SLOT"
BODY_TYPE"PLUMBING"
HDL_TAP"TRUE"
ROOM"RISER1";
"B \NAC \NWC"1;
"S \NAC"
BN"6"109;
%"TAP"
"6","(-3300,4700)","2","standard","I167";
;
CDS_LIB"standard"
BOM_COST"IO_SLOT"
BODY_TYPE"PLUMBING"
HDL_TAP"TRUE"
ROOM"RISER1";
"B \NAC \NWC"2;
"S \NAC"
BN"9"122;
%"TAP"
"6","(-3300,4800)","2","standard","I168";
;
CDS_LIB"standard"
BOM_COST"IO_SLOT"
BODY_TYPE"PLUMBING"
HDL_TAP"TRUE"
ROOM"RISER1";
"B \NAC \NWC"2;
"S \NAC"
BN"8"124;
%"TAP"
"6","(-3450,4850)","2","standard","I169";
;
CDS_LIB"standard"
BOM_COST"IO_SLOT"
BODY_TYPE"PLUMBING"
HDL_TAP"TRUE"
ROOM"RISER1";
"B \NAC \NWC"1;
"S \NAC"
BN"8"125;
%"TAP"
"6","(-3450,4750)","2","standard","I170";
;
CDS_LIB"standard"
BOM_COST"IO_SLOT"
BODY_TYPE"PLUMBING"
HDL_TAP"TRUE"
ROOM"RISER1";
"B \NAC \NWC"1;
"S \NAC"
BN"9"123;
%"TAP"
"6","(-3450,4650)","2","standard","I171";
;
CDS_LIB"standard"
BOM_COST"IO_SLOT"
BODY_TYPE"PLUMBING"
HDL_TAP"TRUE"
ROOM"RISER1";
"B \NAC \NWC"1;
"S \NAC"
BN"10"121;
%"TAP"
"6","(-3300,4600)","2","standard","I172";
;
CDS_LIB"standard"
BOM_COST"IO_SLOT"
BODY_TYPE"PLUMBING"
HDL_TAP"TRUE"
ROOM"RISER1";
"B \NAC \NWC"2;
"S \NAC"
BN"10"120;
%"TAP"
"6","(-3300,4500)","2","standard","I173";
;
CDS_LIB"standard"
BOM_COST"IO_SLOT"
BODY_TYPE"PLUMBING"
HDL_TAP"TRUE"
ROOM"RISER1";
"B \NAC \NWC"2;
"S \NAC"
BN"11"118;
%"TAP"
"6","(-3300,4400)","2","standard","I174";
;
CDS_LIB"standard"
BOM_COST"IO_SLOT"
BODY_TYPE"PLUMBING"
HDL_TAP"TRUE"
ROOM"RISER1";
"B \NAC \NWC"2;
"S \NAC"
BN"12"116;
%"TAP"
"6","(-3450,4550)","2","standard","I175";
;
CDS_LIB"standard"
BOM_COST"IO_SLOT"
BODY_TYPE"PLUMBING"
HDL_TAP"TRUE"
ROOM"RISER1";
"B \NAC \NWC"1;
"S \NAC"
BN"11"119;
%"TAP"
"6","(-3450,4450)","2","standard","I176";
;
CDS_LIB"standard"
BOM_COST"IO_SLOT"
BODY_TYPE"PLUMBING"
HDL_TAP"TRUE"
ROOM"RISER1";
"B \NAC \NWC"1;
"S \NAC"
BN"12"117;
%"TAP"
"6","(-3300,4200)","2","standard","I177";
;
BOM_COST"IO_SLOT"
CDS_LIB"standard"
BODY_TYPE"PLUMBING"
HDL_TAP"TRUE"
ROOM"RISER1";
"B \NAC \NWC"2;
"S \NAC"
BN"14"112;
%"TAP"
"6","(-3300,4100)","2","standard","I178";
;
CDS_LIB"standard"
BOM_COST"IO_SLOT"
BODY_TYPE"PLUMBING"
HDL_TAP"TRUE"
ROOM"RISER1";
"B \NAC \NWC"2;
"S \NAC"
BN"15"110;
%"TAP"
"6","(-3300,4300)","2","standard","I179";
;
CDS_LIB"standard"
BOM_COST"IO_SLOT"
BODY_TYPE"PLUMBING"
HDL_TAP"TRUE"
ROOM"RISER1";
"B \NAC \NWC"2;
"S \NAC"
BN"13"114;
%"TAP"
"6","(-3450,4350)","2","standard","I180";
;
CDS_LIB"standard"
BOM_COST"IO_SLOT"
BODY_TYPE"PLUMBING"
HDL_TAP"TRUE"
ROOM"RISER1";
"B \NAC \NWC"1;
"S \NAC"
BN"13"115;
%"TAP"
"6","(-3450,4250)","2","standard","I181";
;
CDS_LIB"standard"
BOM_COST"IO_SLOT"
BODY_TYPE"PLUMBING"
HDL_TAP"TRUE"
ROOM"RISER1";
"B \NAC \NWC"1;
"S \NAC"
BN"14"113;
%"TAP"
"6","(-3450,4150)","2","standard","I182";
;
CDS_LIB"standard"
BOM_COST"IO_SLOT"
BODY_TYPE"PLUMBING"
HDL_TAP"TRUE"
ROOM"RISER1";
"B \NAC \NWC"1;
"S \NAC"
BN"15"111;
%"TAP"
"6","(-3300,3100)","2","mstr_standard","I185";
;
CDS_LIB"mstr_standard"
BOM_COST"IO_SLOT"
BODY_TYPE"PLUMBING"
HDL_TAP"TRUE"
ROOM"RISER1";
"B \NAC \NWC"4;
"S \NAC"
BN"0"103;
%"TAP"
"6","(-3450,3150)","2","mstr_standard","I186";
;
BOM_COST"IO_SLOT"
CDS_LIB"mstr_standard"
BODY_TYPE"PLUMBING"
HDL_TAP"TRUE"
ROOM"RISER1";
"B \NAC \NWC"3;
"S \NAC"
BN"0"104;
%"TAP"
"6","(-3300,2900)","2","standard","I187";
;
BOM_COST"IO_SLOT"
CDS_LIB"standard"
BODY_TYPE"PLUMBING"
HDL_TAP"TRUE"
ROOM"RISER1";
"B \NAC \NWC"4;
"S \NAC"
BN"2"99;
%"TAP"
"6","(-3300,3000)","2","mstr_standard","I188";
;
BOM_COST"IO_SLOT"
CDS_LIB"mstr_standard"
BODY_TYPE"PLUMBING"
HDL_TAP"TRUE"
ROOM"RISER1";
"B \NAC \NWC"4;
"S \NAC"
BN"1"101;
%"TAP"
"6","(-3450,3050)","2","mstr_standard","I189";
;
BOM_COST"IO_SLOT"
CDS_LIB"mstr_standard"
BODY_TYPE"PLUMBING"
HDL_TAP"TRUE"
ROOM"RISER1";
"B \NAC \NWC"3;
"S \NAC"
BN"1"102;
%"TAP"
"6","(-3450,2950)","2","standard","I190";
;
BOM_COST"IO_SLOT"
CDS_LIB"standard"
BODY_TYPE"PLUMBING"
HDL_TAP"TRUE"
ROOM"RISER1";
"B \NAC \NWC"3;
"S \NAC"
BN"2"100;
%"TAP"
"6","(-3450,2850)","2","standard","I191";
;
BOM_COST"IO_SLOT"
CDS_LIB"standard"
BODY_TYPE"PLUMBING"
HDL_TAP"TRUE"
ROOM"RISER1";
"B \NAC \NWC"3;
"S \NAC"
BN"3"98;
%"TAP"
"6","(-3300,2800)","2","standard","I192";
;
BOM_COST"IO_SLOT"
CDS_LIB"standard"
BODY_TYPE"PLUMBING"
HDL_TAP"TRUE"
ROOM"RISER1";
"B \NAC \NWC"4;
"S \NAC"
BN"3"97;
%"TAP"
"6","(-3300,2700)","2","standard","I193";
;
BOM_COST"IO_SLOT"
CDS_LIB"standard"
BODY_TYPE"PLUMBING"
HDL_TAP"TRUE"
ROOM"RISER1";
"B \NAC \NWC"4;
"S \NAC"
BN"4"95;
%"TAP"
"6","(-3300,2600)","2","standard","I194";
;
BOM_COST"IO_SLOT"
CDS_LIB"standard"
BODY_TYPE"PLUMBING"
HDL_TAP"TRUE"
ROOM"RISER1";
"B \NAC \NWC"4;
"S \NAC"
BN"5"93;
%"TAP"
"6","(-3450,2750)","2","standard","I195";
;
BOM_COST"IO_SLOT"
CDS_LIB"standard"
BODY_TYPE"PLUMBING"
HDL_TAP"TRUE"
ROOM"RISER1";
"B \NAC \NWC"3;
"S \NAC"
BN"4"96;
%"TAP"
"6","(-3450,2650)","2","standard","I196";
;
BOM_COST"IO_SLOT"
CDS_LIB"standard"
BODY_TYPE"PLUMBING"
HDL_TAP"TRUE"
ROOM"RISER1";
"B \NAC \NWC"3;
"S \NAC"
BN"5"94;
%"TAP"
"6","(-3300,2400)","2","standard","I197";
;
BOM_COST"IO_SLOT"
CDS_LIB"standard"
BODY_TYPE"PLUMBING"
HDL_TAP"TRUE"
ROOM"RISER1";
"B \NAC \NWC"4;
"S \NAC"
BN"7"89;
%"TAP"
"6","(-3300,2500)","2","standard","I198";
;
BOM_COST"IO_SLOT"
CDS_LIB"standard"
BODY_TYPE"PLUMBING"
HDL_TAP"TRUE"
ROOM"RISER1";
"B \NAC \NWC"4;
"S \NAC"
BN"6"91;
%"TAP"
"6","(-3450,2550)","2","standard","I199";
;
BOM_COST"IO_SLOT"
CDS_LIB"standard"
BODY_TYPE"PLUMBING"
HDL_TAP"TRUE"
ROOM"RISER1";
"B \NAC \NWC"3;
"S \NAC"
BN"6"92;
%"TAP"
"6","(-3450,2450)","2","standard","I200";
;
BOM_COST"IO_SLOT"
CDS_LIB"standard"
BODY_TYPE"PLUMBING"
HDL_TAP"TRUE"
ROOM"RISER1";
"B \NAC \NWC"3;
"S \NAC"
BN"7"90;
%"TAP"
"6","(-3450,2350)","2","standard","I201";
;
BOM_COST"IO_SLOT"
CDS_LIB"standard"
BODY_TYPE"PLUMBING"
HDL_TAP"TRUE"
ROOM"RISER1";
"B \NAC \NWC"3;
"S \NAC"
BN"8"88;
%"TAP"
"6","(-3300,2300)","2","standard","I202";
;
BOM_COST"IO_SLOT"
CDS_LIB"standard"
BODY_TYPE"PLUMBING"
HDL_TAP"TRUE"
ROOM"RISER1";
"B \NAC \NWC"4;
"S \NAC"
BN"8"87;
%"TAP"
"6","(-3300,2200)","2","standard","I203";
;
BOM_COST"IO_SLOT"
CDS_LIB"standard"
BODY_TYPE"PLUMBING"
HDL_TAP"TRUE"
ROOM"RISER1";
"B \NAC \NWC"4;
"S \NAC"
BN"9"85;
%"TAP"
"6","(-3300,2100)","2","standard","I204";
;
BOM_COST"IO_SLOT"
CDS_LIB"standard"
BODY_TYPE"PLUMBING"
HDL_TAP"TRUE"
ROOM"RISER1";
"B \NAC \NWC"4;
"S \NAC"
BN"10"83;
%"TAP"
"6","(-3450,2250)","2","standard","I205";
;
BOM_COST"IO_SLOT"
CDS_LIB"standard"
BODY_TYPE"PLUMBING"
HDL_TAP"TRUE"
ROOM"RISER1";
"B \NAC \NWC"3;
"S \NAC"
BN"9"86;
%"TAP"
"6","(-3450,2150)","2","standard","I206";
;
BOM_COST"IO_SLOT"
CDS_LIB"standard"
BODY_TYPE"PLUMBING"
HDL_TAP"TRUE"
ROOM"RISER1";
"B \NAC \NWC"3;
"S \NAC"
BN"10"84;
%"TAP"
"6","(-3450,2050)","2","standard","I207";
;
BOM_COST"IO_SLOT"
CDS_LIB"standard"
BODY_TYPE"PLUMBING"
HDL_TAP"TRUE"
ROOM"RISER1";
"B \NAC \NWC"3;
"S \NAC"
BN"11"82;
%"TAP"
"6","(-3300,1800)","2","standard","I208";
;
BOM_COST"IO_SLOT"
CDS_LIB"standard"
BODY_TYPE"PLUMBING"
HDL_TAP"TRUE"
ROOM"RISER1";
"B \NAC \NWC"4;
"S \NAC"
BN"13"77;
%"TAP"
"6","(-3300,1900)","2","standard","I209";
;
BOM_COST"IO_SLOT"
CDS_LIB"standard"
BODY_TYPE"PLUMBING"
HDL_TAP"TRUE"
ROOM"RISER1";
"B \NAC \NWC"4;
"S \NAC"
BN"12"79;
%"TAP"
"6","(-3300,2000)","2","standard","I210";
;
BOM_COST"IO_SLOT"
CDS_LIB"standard"
BODY_TYPE"PLUMBING"
HDL_TAP"TRUE"
ROOM"RISER1";
"B \NAC \NWC"4;
"S \NAC"
BN"11"81;
%"TAP"
"6","(-3450,1950)","2","standard","I211";
;
BOM_COST"IO_SLOT"
CDS_LIB"standard"
BODY_TYPE"PLUMBING"
HDL_TAP"TRUE"
ROOM"RISER1";
"B \NAC \NWC"3;
"S \NAC"
BN"12"80;
%"TAP"
"6","(-3450,1850)","2","standard","I212";
;
BOM_COST"IO_SLOT"
CDS_LIB"standard"
BODY_TYPE"PLUMBING"
HDL_TAP"TRUE"
ROOM"RISER1";
"B \NAC \NWC"3;
"S \NAC"
BN"13"78;
%"TAP"
"6","(-3300,1600)","2","standard","I213";
;
BOM_COST"IO_SLOT"
CDS_LIB"standard"
BODY_TYPE"PLUMBING"
HDL_TAP"TRUE"
ROOM"RISER1";
"B \NAC \NWC"4;
"S \NAC"
BN"15"73;
%"TAP"
"6","(-3300,1700)","2","standard","I214";
;
CDS_LIB"standard"
BOM_COST"IO_SLOT"
BODY_TYPE"PLUMBING"
HDL_TAP"TRUE"
ROOM"RISER1";
"B \NAC \NWC"4;
"S \NAC"
BN"14"75;
%"TAP"
"6","(-3450,1750)","2","standard","I215";
;
BOM_COST"IO_SLOT"
CDS_LIB"standard"
BODY_TYPE"PLUMBING"
HDL_TAP"TRUE"
ROOM"RISER1";
"B \NAC \NWC"3;
"S \NAC"
BN"14"76;
%"TAP"
"6","(-3450,1650)","2","standard","I216";
;
BOM_COST"IO_SLOT"
CDS_LIB"standard"
BODY_TYPE"PLUMBING"
HDL_TAP"TRUE"
ROOM"RISER1";
"B \NAC \NWC"3;
"S \NAC"
BN"15"74;
%"TAP"
"6","(-5875,3150)","0","mstr_standard","I251";
;
CDS_LIB"mstr_standard"
BODY_TYPE"PLUMBING"
HDL_TAP"TRUE";
"B \NAC \NWC"7;
"S \NAC"
BN"0"48;
%"TAP"
"6","(-5875,2950)","0","mstr_standard","I253";
;
CDS_LIB"mstr_standard"
BODY_TYPE"PLUMBING"
HDL_TAP"TRUE";
"B \NAC \NWC"7;
"S \NAC"
BN"2"44;
%"TAP"
"6","(-5875,3050)","0","mstr_standard","I254";
;
CDS_LIB"mstr_standard"
BODY_TYPE"PLUMBING"
HDL_TAP"TRUE";
"B \NAC \NWC"7;
"S \NAC"
BN"1"46;
%"TAP"
"6","(-5875,2850)","0","standard","I255";
;
CDS_LIB"standard"
BODY_TYPE"PLUMBING"
HDL_TAP"TRUE";
"B \NAC \NWC"7;
"S \NAC"
BN"3"42;
%"TAP"
"6","(-5875,2750)","0","standard","I256";
;
CDS_LIB"standard"
BODY_TYPE"PLUMBING"
HDL_TAP"TRUE";
"B \NAC \NWC"7;
"S \NAC"
BN"4"40;
%"TAP"
"6","(-5875,2650)","0","standard","I257";
;
CDS_LIB"standard"
BODY_TYPE"PLUMBING"
HDL_TAP"TRUE";
"B \NAC \NWC"7;
"S \NAC"
BN"5"38;
%"TAP"
"6","(-5875,2550)","0","standard","I263";
;
CDS_LIB"standard"
BODY_TYPE"PLUMBING"
HDL_TAP"TRUE";
"B \NAC \NWC"7;
"S \NAC"
BN"6"36;
%"TAP"
"6","(-5875,2450)","0","mstr_standard","I285";
;
CDS_LIB"mstr_standard"
BODY_TYPE"PLUMBING"
HDL_TAP"TRUE";
"B \NAC \NWC"7;
"S \NAC"
BN"7"34;
%"TAP"
"6","(-5875,2050)","0","standard","I286";
;
CDS_LIB"standard"
BODY_TYPE"PLUMBING"
HDL_TAP"TRUE";
"B \NAC \NWC"7;
"S \NAC"
BN"11"26;
%"TAP"
"6","(-5875,1950)","0","standard","I287";
;
CDS_LIB"standard"
BODY_TYPE"PLUMBING"
HDL_TAP"TRUE";
"B \NAC \NWC"7;
"S \NAC"
BN"12"24;
%"TAP"
"6","(-5875,1850)","0","standard","I288";
;
CDS_LIB"standard"
BODY_TYPE"PLUMBING"
HDL_TAP"TRUE";
"B \NAC \NWC"7;
"S \NAC"
BN"13"22;
%"TAP"
"6","(-5875,2350)","0","mstr_standard","I292";
;
CDS_LIB"mstr_standard"
BODY_TYPE"PLUMBING"
HDL_TAP"TRUE";
"B \NAC \NWC"7;
"S \NAC"
BN"8"32;
%"TAP"
"6","(-5875,2250)","0","mstr_standard","I293";
;
CDS_LIB"mstr_standard"
BODY_TYPE"PLUMBING"
HDL_TAP"TRUE";
"B \NAC \NWC"7;
"S \NAC"
BN"9"30;
%"TAP"
"6","(-5875,2150)","0","standard","I294";
;
CDS_LIB"standard"
BODY_TYPE"PLUMBING"
HDL_TAP"TRUE";
"B \NAC \NWC"7;
"S \NAC"
BN"10"28;
%"TAP"
"6","(-5875,1750)","0","standard","I299";
;
CDS_LIB"standard"
BODY_TYPE"PLUMBING"
HDL_TAP"TRUE";
"B \NAC \NWC"7;
"S \NAC"
BN"14"20;
%"TAP"
"6","(-5875,1650)","0","standard","I302";
;
CDS_LIB"standard"
BODY_TYPE"PLUMBING"
HDL_TAP"TRUE";
"B \NAC \NWC"7;
"S \NAC"
BN"15"18;
%"TAP"
"6","(-6025,3000)","0","mstr_standard","I303";
;
CDS_LIB"mstr_standard"
BODY_TYPE"PLUMBING"
HDL_TAP"TRUE";
"B \NAC \NWC"8;
"S \NAC"
BN"1"45;
%"TAP"
"6","(-6025,3100)","0","mstr_standard","I304";
;
CDS_LIB"mstr_standard"
BODY_TYPE"PLUMBING"
HDL_TAP"TRUE";
"B \NAC \NWC"8;
"S \NAC"
BN"0"47;
%"TAP"
"6","(-6025,2900)","0","standard","I305";
;
CDS_LIB"standard"
BODY_TYPE"PLUMBING"
HDL_TAP"TRUE";
"B \NAC \NWC"8;
"S \NAC"
BN"2"43;
%"TAP"
"6","(-6025,2800)","0","standard","I306";
;
CDS_LIB"standard"
BODY_TYPE"PLUMBING"
HDL_TAP"TRUE";
"B \NAC \NWC"8;
"S \NAC"
BN"3"41;
%"TAP"
"6","(-6025,2700)","0","standard","I307";
;
CDS_LIB"standard"
BODY_TYPE"PLUMBING"
HDL_TAP"TRUE";
"B \NAC \NWC"8;
"S \NAC"
BN"4"39;
%"TAP"
"6","(-6025,2600)","0","standard","I308";
;
CDS_LIB"standard"
BODY_TYPE"PLUMBING"
HDL_TAP"TRUE";
"B \NAC \NWC"8;
"S \NAC"
BN"5"37;
%"TAP"
"6","(-6025,2500)","0","standard","I309";
;
CDS_LIB"standard"
BODY_TYPE"PLUMBING"
HDL_TAP"TRUE";
"B \NAC \NWC"8;
"S \NAC"
BN"6"35;
%"TAP"
"6","(-6025,2400)","0","mstr_standard","I310";
;
CDS_LIB"mstr_standard"
BODY_TYPE"PLUMBING"
HDL_TAP"TRUE";
"B \NAC \NWC"8;
"S \NAC"
BN"7"33;
%"TAP"
"6","(-6025,2200)","0","standard","I311";
;
CDS_LIB"standard"
BODY_TYPE"PLUMBING"
HDL_TAP"TRUE";
"B \NAC \NWC"8;
"S \NAC"
BN"9"29;
%"TAP"
"6","(-6025,2300)","0","mstr_standard","I312";
;
CDS_LIB"mstr_standard"
BODY_TYPE"PLUMBING"
HDL_TAP"TRUE";
"B \NAC \NWC"8;
"S \NAC"
BN"8"31;
%"TAP"
"6","(-6025,2100)","0","standard","I313";
;
CDS_LIB"standard"
BODY_TYPE"PLUMBING"
HDL_TAP"TRUE";
"B \NAC \NWC"8;
"S \NAC"
BN"10"27;
%"TAP"
"6","(-6025,2000)","0","standard","I314";
;
CDS_LIB"standard"
BODY_TYPE"PLUMBING"
HDL_TAP"TRUE";
"B \NAC \NWC"8;
"S \NAC"
BN"11"25;
%"TAP"
"6","(-6025,1900)","0","standard","I315";
;
CDS_LIB"standard"
BODY_TYPE"PLUMBING"
HDL_TAP"TRUE";
"B \NAC \NWC"8;
"S \NAC"
BN"12"23;
%"TAP"
"6","(-6025,1800)","0","standard","I316";
;
CDS_LIB"standard"
BODY_TYPE"PLUMBING"
HDL_TAP"TRUE";
"B \NAC \NWC"8;
"S \NAC"
BN"13"21;
%"TAP"
"6","(-6025,1700)","0","standard","I317";
;
CDS_LIB"standard"
BODY_TYPE"PLUMBING"
HDL_TAP"TRUE";
"B \NAC \NWC"8;
"S \NAC"
BN"14"19;
%"TAP"
"6","(-6025,1600)","0","standard","I318";
;
CDS_LIB"standard"
BODY_TYPE"PLUMBING"
HDL_TAP"TRUE";
"B \NAC \NWC"8;
"S \NAC"
BN"15"17;
%"TAP"
"6","(-5875,5650)","0","mstr_standard","I321";
;
CDS_LIB"mstr_standard"
BODY_TYPE"PLUMBING"
HDL_TAP"TRUE";
"B \NAC \NWC"5;
"S \NAC"
BN"0"13;
%"TAP"
"6","(-5875,5550)","0","mstr_standard","I322";
;
CDS_LIB"mstr_standard"
BODY_TYPE"PLUMBING"
HDL_TAP"TRUE";
"B \NAC \NWC"5;
"S \NAC"
BN"1"15;
%"TAP"
"6","(-5875,5450)","0","mstr_standard","I323";
;
CDS_LIB"mstr_standard"
BODY_TYPE"PLUMBING"
HDL_TAP"TRUE";
"B \NAC \NWC"5;
"S \NAC"
BN"2"72;
%"TAP"
"6","(-6025,5600)","0","mstr_standard","I324";
;
CDS_LIB"mstr_standard"
BODY_TYPE"PLUMBING"
HDL_TAP"TRUE";
"B \NAC \NWC"6;
"S \NAC"
BN"0"14;
%"TAP"
"6","(-6025,5500)","0","mstr_standard","I325";
;
CDS_LIB"mstr_standard"
BODY_TYPE"PLUMBING"
HDL_TAP"TRUE";
"B \NAC \NWC"6;
"S \NAC"
BN"1"70;
%"TAP"
"6","(-6025,5400)","0","standard","I326";
;
CDS_LIB"standard"
BODY_TYPE"PLUMBING"
HDL_TAP"TRUE";
"B \NAC \NWC"6;
"S \NAC"
BN"2"68;
%"TAP"
"6","(-5875,5150)","0","standard","I327";
;
CDS_LIB"standard"
BODY_TYPE"PLUMBING"
HDL_TAP"TRUE";
"B \NAC \NWC"5;
"S \NAC"
BN"5"12;
%"TAP"
"6","(-5875,5350)","0","standard","I328";
;
CDS_LIB"standard"
BODY_TYPE"PLUMBING"
HDL_TAP"TRUE";
"B \NAC \NWC"5;
"S \NAC"
BN"3"71;
%"TAP"
"6","(-5875,5250)","0","standard","I329";
;
CDS_LIB"standard"
BODY_TYPE"PLUMBING"
HDL_TAP"TRUE";
"B \NAC \NWC"5;
"S \NAC"
BN"4"69;
%"TAP"
"6","(-6025,5200)","0","standard","I330";
;
CDS_LIB"standard"
BODY_TYPE"PLUMBING"
HDL_TAP"TRUE";
"B \NAC \NWC"6;
"S \NAC"
BN"4"67;
%"TAP"
"6","(-6025,5300)","0","standard","I331";
;
CDS_LIB"standard"
BODY_TYPE"PLUMBING"
HDL_TAP"TRUE";
"B \NAC \NWC"6;
"S \NAC"
BN"3"16;
%"TAP"
"6","(-5875,5050)","0","standard","I332";
;
CDS_LIB"standard"
BODY_TYPE"PLUMBING"
HDL_TAP"TRUE";
"B \NAC \NWC"5;
"S \NAC"
BN"6"10;
%"TAP"
"6","(-5875,4850)","0","standard","I333";
;
CDS_LIB"standard"
BODY_TYPE"PLUMBING"
HDL_TAP"TRUE";
"B \NAC \NWC"5;
"S \NAC"
BN"8"66;
%"TAP"
"6","(-5875,4950)","0","standard","I334";
;
CDS_LIB"standard"
BODY_TYPE"PLUMBING"
HDL_TAP"TRUE";
"B \NAC \NWC"5;
"S \NAC"
BN"7"51;
%"TAP"
"6","(-6025,4900)","0","standard","I335";
;
CDS_LIB"standard"
BODY_TYPE"PLUMBING"
HDL_TAP"TRUE";
"B \NAC \NWC"6;
"S \NAC"
BN"7"49;
%"TAP"
"6","(-6025,5000)","0","standard","I336";
;
CDS_LIB"standard"
BODY_TYPE"PLUMBING"
HDL_TAP"TRUE";
"B \NAC \NWC"6;
"S \NAC"
BN"6"50;
%"TAP"
"6","(-6025,5100)","0","standard","I337";
;
CDS_LIB"standard"
BODY_TYPE"PLUMBING"
HDL_TAP"TRUE";
"B \NAC \NWC"6;
"S \NAC"
BN"5"11;
%"TAP"
"6","(-5875,4750)","0","standard","I338";
;
CDS_LIB"standard"
BODY_TYPE"PLUMBING"
HDL_TAP"TRUE";
"B \NAC \NWC"5;
"S \NAC"
BN"9"64;
%"TAP"
"6","(-5875,4650)","0","standard","I339";
;
CDS_LIB"standard"
BODY_TYPE"PLUMBING"
HDL_TAP"TRUE";
"B \NAC \NWC"5;
"S \NAC"
BN"10"63;
%"TAP"
"6","(-6025,4700)","0","standard","I340";
;
CDS_LIB"standard"
BODY_TYPE"PLUMBING"
HDL_TAP"TRUE";
"B \NAC \NWC"6;
"S \NAC"
BN"9"9;
%"TAP"
"6","(-6025,4800)","0","standard","I341";
;
CDS_LIB"standard"
BODY_TYPE"PLUMBING"
HDL_TAP"TRUE";
"B \NAC \NWC"6;
"S \NAC"
BN"8"65;
%"TAP"
"6","(-5875,4550)","0","standard","I342";
;
CDS_LIB"standard"
BODY_TYPE"PLUMBING"
HDL_TAP"TRUE";
"B \NAC \NWC"5;
"S \NAC"
BN"11"61;
%"TAP"
"6","(-5875,4350)","0","standard","I343";
;
CDS_LIB"standard"
BODY_TYPE"PLUMBING"
HDL_TAP"TRUE";
"B \NAC \NWC"5;
"S \NAC"
BN"13"57;
%"TAP"
"6","(-5875,4450)","0","standard","I344";
;
CDS_LIB"standard"
BODY_TYPE"PLUMBING"
HDL_TAP"TRUE";
"B \NAC \NWC"5;
"S \NAC"
BN"12"59;
%"TAP"
"6","(-6025,4400)","0","standard","I345";
;
CDS_LIB"standard"
BODY_TYPE"PLUMBING"
HDL_TAP"TRUE";
"B \NAC \NWC"6;
"S \NAC"
BN"12"58;
%"TAP"
"6","(-6025,4500)","0","standard","I346";
;
CDS_LIB"standard"
BODY_TYPE"PLUMBING"
HDL_TAP"TRUE";
"B \NAC \NWC"6;
"S \NAC"
BN"11"60;
%"TAP"
"6","(-6025,4600)","0","standard","I347";
;
CDS_LIB"standard"
BODY_TYPE"PLUMBING"
HDL_TAP"TRUE";
"B \NAC \NWC"6;
"S \NAC"
BN"10"62;
%"TAP"
"6","(-5875,4250)","0","standard","I348";
;
CDS_LIB"standard"
BODY_TYPE"PLUMBING"
HDL_TAP"TRUE";
"B \NAC \NWC"5;
"S \NAC"
BN"14"55;
%"TAP"
"6","(-5875,4150)","0","standard","I349";
;
CDS_LIB"standard"
BODY_TYPE"PLUMBING"
HDL_TAP"TRUE";
"B \NAC \NWC"5;
"S \NAC"
BN"15"53;
%"TAP"
"6","(-6025,4300)","0","standard","I350";
;
CDS_LIB"standard"
BODY_TYPE"PLUMBING"
HDL_TAP"TRUE";
"B \NAC \NWC"6;
"S \NAC"
BN"13"56;
%"TAP"
"6","(-6025,4100)","0","standard","I351";
;
CDS_LIB"standard"
BODY_TYPE"PLUMBING"
HDL_TAP"TRUE";
"B \NAC \NWC"6;
"S \NAC"
BN"15"52;
%"TAP"
"6","(-6025,4200)","0","standard","I352";
;
CDS_LIB"standard"
BODY_TYPE"PLUMBING"
HDL_TAP"TRUE";
"B \NAC \NWC"6;
"S \NAC"
BN"14"54;
END.
